(kicad_pcb
	(version 20241229)
	(generator "pcbnew")
	(generator_version "9.0")
	(general
		(thickness 1.63)
		(legacy_teardrops no)
	)
	(paper "A4")
	(title_block
		(title "CM4 Baseboard")
		(date "2026-01-05")
		(rev "1.1.1")
		(company "Antmicro Ltd")
		(comment 1 "www.antmicro.com")
		(comment 9 "footprints 175-179 of 506")
	)
	(layers
		(0 "F.Cu" signal)
		(4 "In1.Cu" power)
		(6 "In2.Cu" power)
		(8 "In3.Cu" signal)
		(10 "In4.Cu" signal)
		(2 "B.Cu" signal)
		(9 "F.Adhes" user "F.Adhesive")
		(11 "B.Adhes" user "B.Adhesive")
		(13 "F.Paste" user)
		(15 "B.Paste" user)
		(5 "F.SilkS" user "F.Silkscreen")
		(7 "B.SilkS" user "B.Silkscreen")
		(1 "F.Mask" user)
		(3 "B.Mask" user)
		(17 "Dwgs.User" user "User.Drawings")
		(19 "Cmts.User" user "User.Comments")
		(21 "Eco1.User" user "User.Eco1")
		(23 "Eco2.User" user "User.Eco2")
		(25 "Edge.Cuts" user)
		(27 "Margin" user)
		(31 "F.CrtYd" user "F.Courtyard")
		(29 "B.CrtYd" user "B.Courtyard")
		(35 "F.Fab" user)
		(33 "B.Fab" user)
	)
	(footprint "antmicro-footprints:C_0402_1005Metric"
		(layer "F.Cu")
		(at 87.467962 146.5665 -90)
		(descr "Capacitor SMD 0402")
		(tags "capacitor SMD 0402")
		(property "Reference" "C926"
			(at 0.7 -0.65 90)
			(layer "F.SilkS")
			(effects
				(font
					(size 0.7 0.7)
					(thickness 0.15)
				)
				(justify right bottom)
			)
		)
		(property "Value" "C_18p_0402"
			(at -1.022927 2.155213 90)
			(layer "F.Fab")
			(effects
				(font
					(size 0.7 0.7)
					(thickness 0.15)
				)
				(justify right bottom)
			)
		)
		(property "Datasheet" "https://product.samsungsem.com/mlcc/CL05C180JB51PN.do"
			(at 0 0 270)
			(layer "F.Fab")
			(hide yes)
			(effects
				(font
					(size 1.27 1.27)
					(thickness 0.15)
				)
			)
		)
		(property "Manufacturer" "Samsung Electro-Mechanics"
			(at 0 0 270)
			(unlocked yes)
			(layer "F.Fab")
			(hide yes)
			(effects
				(font
					(size 1 1)
					(thickness 0.15)
				)
			)
		)
		(property "MPN" "CL05C180JB51PNC"
			(at 0 0 270)
			(unlocked yes)
			(layer "F.Fab")
			(hide yes)
			(effects
				(font
					(size 1 1)
					(thickness 0.15)
				)
			)
		)
		(property "Val" "18p"
			(at 0 0 270)
			(unlocked yes)
			(layer "F.Fab")
			(hide yes)
			(effects
				(font
					(size 1 1)
					(thickness 0.15)
				)
			)
		)
		(property "License" "Apache-2.0"
			(at 0 0 270)
			(unlocked yes)
			(layer "F.Fab")
			(hide yes)
			(effects
				(font
					(size 1 1)
					(thickness 0.15)
				)
			)
		)
		(property "Author" "Antmicro"
			(at 0 0 270)
			(unlocked yes)
			(layer "F.Fab")
			(hide yes)
			(effects
				(font
					(size 1 1)
					(thickness 0.15)
				)
			)
		)
		(property "Voltage" ""
			(at 0 0 270)
			(unlocked yes)
			(layer "F.Fab")
			(hide yes)
			(effects
				(font
					(size 1 1)
					(thickness 0.15)
				)
			)
		)
		(property "Dielectric" ""
			(at 0 0 270)
			(unlocked yes)
			(layer "F.Fab")
			(hide yes)
			(effects
				(font
					(size 1 1)
					(thickness 0.15)
				)
			)
		)
		(sheetname "/USB/")
		(sheetfile "usb.kicad_sch")
		(attr smd)
		(fp_rect
			(start -0.925 -0.47)
			(end 0.925 0.47)
			(stroke
				(width 0.05)
				(type default)
			)
			(fill no)
			(layer "F.CrtYd")
		)
		(fp_line
			(start -0.494 0.248)
			(end -0.494 -0.25)
			(stroke
				(width 0.15)
				(type solid)
			)
			(layer "F.Fab")
		)
		(fp_line
			(start 0.504 0.248)
			(end -0.494 0.248)
			(stroke
				(width 0.15)
				(type solid)
			)
			(layer "F.Fab")
		)
		(fp_line
			(start -0.494 -0.25)
			(end 0.504 -0.25)
			(stroke
				(width 0.15)
				(type solid)
			)
			(layer "F.Fab")
		)
		(fp_line
			(start 0.504 -0.25)
			(end 0.504 0.248)
			(stroke
				(width 0.15)
				(type solid)
			)
			(layer "F.Fab")
		)
		(fp_text user "License: Apache-2.0"
			(at -0.939 5.799 270)
			(layer "F.Fab")
			(effects
				(font
					(size 0.7 0.7)
					(thickness 0.15)
				)
				(justify left bottom)
			)
		)
		(fp_text user "${REFERENCE}"
			(at -0.939 4.599 270)
			(layer "F.Fab")
			(effects
				(font
					(size 0.7 0.7)
					(thickness 0.15)
				)
				(justify left bottom)
			)
		)
		(fp_text user "Author: Antmicro"
			(at -0.939 3.399 270)
			(layer "F.Fab")
			(effects
				(font
					(size 0.7 0.7)
					(thickness 0.15)
				)
				(justify left bottom)
			)
		)
		(pad "1" smd roundrect
			(at -0.48 0 270)
			(size 0.59 0.64)
			(layers "F.Cu" "F.Mask" "F.Paste")
			(roundrect_rratio 0.25)
			(net 114 "Net-(U905-OSCI)")
			(pintype "passive")
		)
		(pad "2" smd roundrect
			(at 0.48 0 270)
			(size 0.59 0.64)
			(layers "F.Cu" "F.Mask" "F.Paste")
			(roundrect_rratio 0.25)
			(net 3 "GND")
			(pintype "passive")
		)
	)
	(footprint "antmicro-footprints:R_0603_1608Metric"
		(layer "F.Cu")
		(at 50.557962 125.2365)
		(descr "Resistor SMD 0603")
		(tags "resistor SMD 0603")
		(property "Reference" "R404"
			(at -1.39 -0.82 0)
			(layer "F.SilkS")
			(effects
				(font
					(size 0.7 0.7)
					(thickness 0.15)
				)
				(justify left bottom)
			)
		)
		(property "Value" "R_63R4_0603"
			(at 0 1.6 0)
			(layer "F.Fab")
			(effects
				(font
					(size 0.7 0.7)
					(thickness 0.15)
				)
				(justify left bottom)
			)
		)
		(property "Datasheet" "https://www.bourns.com/docs/product-datasheets/cr.pdf"
			(at 0 0 0)
			(layer "F.Fab")
			(hide yes)
			(effects
				(font
					(size 1.27 1.27)
					(thickness 0.15)
				)
			)
		)
		(property "Manufacturer" "Bourns"
			(at 0 0 0)
			(unlocked yes)
			(layer "F.Fab")
			(hide yes)
			(effects
				(font
					(size 1 1)
					(thickness 0.15)
				)
			)
		)
		(property "MPN" "CR0603-FX-63R4ELF"
			(at 0 0 0)
			(unlocked yes)
			(layer "F.Fab")
			(hide yes)
			(effects
				(font
					(size 1 1)
					(thickness 0.15)
				)
			)
		)
		(property "Val" "63R4"
			(at 0 0 0)
			(unlocked yes)
			(layer "F.Fab")
			(hide yes)
			(effects
				(font
					(size 1 1)
					(thickness 0.15)
				)
			)
		)
		(property "License" "Apache-2.0"
			(at 0 0 0)
			(unlocked yes)
			(layer "F.Fab")
			(hide yes)
			(effects
				(font
					(size 1 1)
					(thickness 0.15)
				)
			)
		)
		(property "Author" "Antmicro"
			(at 0 0 0)
			(unlocked yes)
			(layer "F.Fab")
			(hide yes)
			(effects
				(font
					(size 1 1)
					(thickness 0.15)
				)
			)
		)
		(property "Tolerance" "1%"
			(at 0 0 0)
			(unlocked yes)
			(layer "F.Fab")
			(hide yes)
			(effects
				(font
					(size 1 1)
					(thickness 0.15)
				)
			)
		)
		(sheetname "/Ethernet/")
		(sheetfile "ethernet.kicad_sch")
		(attr smd)
		(fp_line
			(start -0.15 -0.4)
			(end 0.15 -0.4)
			(stroke
				(width 0.15)
				(type solid)
			)
			(layer "F.SilkS")
		)
		(fp_line
			(start -0.15 0.4)
			(end 0.15 0.4)
			(stroke
				(width 0.15)
				(type solid)
			)
			(layer "F.SilkS")
		)
		(fp_rect
			(start -1.25 -0.65)
			(end 1.25 0.65)
			(stroke
				(width 0.05)
				(type solid)
			)
			(fill no)
			(layer "F.CrtYd")
		)
		(fp_rect
			(start -0.8 -0.4)
			(end 0.8 0.4)
			(stroke
				(width 0.15)
				(type solid)
			)
			(fill no)
			(layer "F.Fab")
		)
		(fp_text user "Author: Antmicro"
			(at -1.25 4.9 0)
			(layer "F.Fab")
			(effects
				(font
					(size 0.7 0.7)
					(thickness 0.15)
				)
				(justify left bottom)
			)
		)
		(fp_text user "${REFERENCE}"
			(at -1.25 3.898 0)
			(layer "F.Fab")
			(effects
				(font
					(size 0.7 0.7)
					(thickness 0.15)
				)
				(justify left bottom)
			)
		)
		(fp_text user "License: Apache-2.0"
			(at -1.25 5.9 0)
			(layer "F.Fab")
			(effects
				(font
					(size 0.7 0.7)
					(thickness 0.15)
				)
				(justify left bottom)
			)
		)
		(pad "1" smd roundrect
			(at -0.7 0)
			(size 0.8 1)
			(layers "F.Cu" "F.Mask" "F.Paste")
			(roundrect_rratio 0.2)
			(net 90 "/Ethernet/VSS")
			(pintype "passive")
		)
		(pad "2" smd roundrect
			(at 0.7 0)
			(size 0.8 1)
			(layers "F.Cu" "F.Mask" "F.Paste")
			(roundrect_rratio 0.2)
			(net 359 "/Ethernet/CLSA")
			(pintype "passive")
		)
	)
	(footprint "antmicro-footprints:C_0402_1005Metric"
		(layer "F.Cu")
		(at 89.667962 131.4765 180)
		(descr "Capacitor SMD 0402")
		(tags "capacitor SMD 0402")
		(property "Reference" "C910"
			(at -1.39 4.060736 0)
			(layer "F.SilkS")
			(effects
				(font
					(size 0.7 0.7)
					(thickness 0.15)
				)
				(justify right bottom)
			)
		)
		(property "Value" "C_100n_0402"
			(at -1.022927 2.155213 0)
			(layer "F.Fab")
			(effects
				(font
					(size 0.7 0.7)
					(thickness 0.15)
				)
				(justify right bottom)
			)
		)
		(property "Datasheet" "https://www.murata.com/products/productdetail?partno=GRM155R61H104KE14%23"
			(at 0 0 180)
			(layer "F.Fab")
			(hide yes)
			(effects
				(font
					(size 1.27 1.27)
					(thickness 0.15)
				)
			)
		)
		(property "Manufacturer" "Murata"
			(at 0 0 180)
			(unlocked yes)
			(layer "F.Fab")
			(hide yes)
			(effects
				(font
					(size 1 1)
					(thickness 0.15)
				)
			)
		)
		(property "MPN" "GRM155R61H104KE14D"
			(at 0 0 180)
			(unlocked yes)
			(layer "F.Fab")
			(hide yes)
			(effects
				(font
					(size 1 1)
					(thickness 0.15)
				)
			)
		)
		(property "Val" "100n"
			(at 0 0 180)
			(unlocked yes)
			(layer "F.Fab")
			(hide yes)
			(effects
				(font
					(size 1 1)
					(thickness 0.15)
				)
			)
		)
		(property "License" "Apache-2.0"
			(at 0 0 180)
			(unlocked yes)
			(layer "F.Fab")
			(hide yes)
			(effects
				(font
					(size 1 1)
					(thickness 0.15)
				)
			)
		)
		(property "Author" "Antmicro"
			(at 0 0 180)
			(unlocked yes)
			(layer "F.Fab")
			(hide yes)
			(effects
				(font
					(size 1 1)
					(thickness 0.15)
				)
			)
		)
		(property "Voltage" "50V"
			(at 0 0 180)
			(unlocked yes)
			(layer "F.Fab")
			(hide yes)
			(effects
				(font
					(size 1 1)
					(thickness 0.15)
				)
			)
		)
		(property "Dielectric" "X5R"
			(at 0 0 180)
			(unlocked yes)
			(layer "F.Fab")
			(hide yes)
			(effects
				(font
					(size 1 1)
					(thickness 0.15)
				)
			)
		)
		(sheetname "/USB/")
		(sheetfile "usb.kicad_sch")
		(attr smd)
		(fp_rect
			(start -0.925 -0.47)
			(end 0.925 0.47)
			(stroke
				(width 0.05)
				(type default)
			)
			(fill no)
			(layer "F.CrtYd")
		)
		(fp_line
			(start 0.504 0.248)
			(end -0.494 0.248)
			(stroke
				(width 0.15)
				(type solid)
			)
			(layer "F.Fab")
		)
		(fp_line
			(start 0.504 -0.25)
			(end 0.504 0.248)
			(stroke
				(width 0.15)
				(type solid)
			)
			(layer "F.Fab")
		)
		(fp_line
			(start -0.494 0.248)
			(end -0.494 -0.25)
			(stroke
				(width 0.15)
				(type solid)
			)
			(layer "F.Fab")
		)
		(fp_line
			(start -0.494 -0.25)
			(end 0.504 -0.25)
			(stroke
				(width 0.15)
				(type solid)
			)
			(layer "F.Fab")
		)
		(fp_text user "License: Apache-2.0"
			(at -0.939 5.799 180)
			(layer "F.Fab")
			(effects
				(font
					(size 0.7 0.7)
					(thickness 0.15)
				)
				(justify left bottom)
			)
		)
		(fp_text user "Author: Antmicro"
			(at -0.939 3.399 180)
			(layer "F.Fab")
			(effects
				(font
					(size 0.7 0.7)
					(thickness 0.15)
				)
				(justify left bottom)
			)
		)
		(fp_text user "${REFERENCE}"
			(at -0.939 4.599 180)
			(layer "F.Fab")
			(effects
				(font
					(size 0.7 0.7)
					(thickness 0.15)
				)
				(justify left bottom)
			)
		)
		(pad "1" smd roundrect
			(at -0.48 0 180)
			(size 0.59 0.64)
			(layers "F.Cu" "F.Mask" "F.Paste")
			(roundrect_rratio 0.25)
			(net 211 "/USB/VCC_PD")
			(pintype "passive")
		)
		(pad "2" smd roundrect
			(at 0.48 0 180)
			(size 0.59 0.64)
			(layers "F.Cu" "F.Mask" "F.Paste")
			(roundrect_rratio 0.25)
			(net 3 "GND")
			(pintype "passive")
		)
	)
	(footprint "antmicro-footprints:R_0402_1005Metric"
		(layer "F.Cu")
		(at 88.792962 122.1165)
		(descr "Resistor SMD 0402")
		(tags "resistor SMD 0402")
		(property "Reference" "R901"
			(at -1.175 1.3 0)
			(layer "F.SilkS")
			(effects
				(font
					(size 0.7 0.7)
					(thickness 0.15)
				)
				(justify left bottom)
			)
		)
		(property "Value" "R_1k_0402"
			(at -1.011843 1.772047 0)
			(layer "F.Fab")
			(effects
				(font
					(size 0.7 0.7)
					(thickness 0.15)
				)
				(justify left bottom)
			)
		)
		(property "Datasheet" "https://www.bourns.com/docs/product-datasheets/cr.pdf"
			(at 0 0 0)
			(layer "F.Fab")
			(hide yes)
			(effects
				(font
					(size 1.27 1.27)
					(thickness 0.15)
				)
			)
		)
		(property "MPN" "CR0402-FX-1001GLF"
			(at 0 0 0)
			(unlocked yes)
			(layer "F.Fab")
			(hide yes)
			(effects
				(font
					(size 1 1)
					(thickness 0.15)
				)
			)
		)
		(property "Manufacturer" "Bourns"
			(at 0 0 0)
			(unlocked yes)
			(layer "F.Fab")
			(hide yes)
			(effects
				(font
					(size 1 1)
					(thickness 0.15)
				)
			)
		)
		(property "License" "Apache-2.0"
			(at 0 0 0)
			(unlocked yes)
			(layer "F.Fab")
			(hide yes)
			(effects
				(font
					(size 1 1)
					(thickness 0.15)
				)
			)
		)
		(property "Author" "Antmicro"
			(at 0 0 0)
			(unlocked yes)
			(layer "F.Fab")
			(hide yes)
			(effects
				(font
					(size 1 1)
					(thickness 0.15)
				)
			)
		)
		(property "Val" "1k"
			(at 0 0 0)
			(unlocked yes)
			(layer "F.Fab")
			(hide yes)
			(effects
				(font
					(size 1 1)
					(thickness 0.15)
				)
			)
		)
		(property "Tolerance" "1%"
			(at 0 0 0)
			(unlocked yes)
			(layer "F.Fab")
			(hide yes)
			(effects
				(font
					(size 1 1)
					(thickness 0.15)
				)
			)
		)
		(sheetname "/USB/")
		(sheetfile "usb.kicad_sch")
		(attr smd)
		(fp_rect
			(start -0.925 -0.47)
			(end 0.925 0.47)
			(stroke
				(width 0.05)
				(type default)
			)
			(fill no)
			(layer "F.CrtYd")
		)
		(fp_rect
			(start -0.5 -0.25)
			(end 0.5 0.25)
			(stroke
				(width 0.15)
				(type solid)
			)
			(fill no)
			(layer "F.Fab")
		)
		(fp_text user "License: Apache-2.0"
			(at -0.95 5.169 0)
			(layer "F.Fab")
			(effects
				(font
					(size 0.7 0.7)
					(thickness 0.15)
				)
				(justify left bottom)
			)
		)
		(fp_text user "Author: Antmicro"
			(at -0.95 4.169 0)
			(layer "F.Fab")
			(effects
				(font
					(size 0.7 0.7)
					(thickness 0.15)
				)
				(justify left bottom)
			)
		)
		(fp_text user "${REFERENCE}"
			(at -0.95 3.168 0)
			(layer "F.Fab")
			(effects
				(font
					(size 0.7 0.7)
					(thickness 0.15)
				)
				(justify left bottom)
			)
		)
		(pad "1" smd roundrect
			(at -0.48 0)
			(size 0.59 0.64)
			(layers "F.Cu" "F.Mask" "F.Paste")
			(roundrect_rratio 0.25)
			(net 482 "Net-(D905-A)")
			(pintype "passive")
		)
		(pad "2" smd roundrect
			(at 0.48 0)
			(size 0.59 0.64)
			(layers "F.Cu" "F.Mask" "F.Paste")
			(roundrect_rratio 0.25)
			(net 24 "/Compute module/USBA_VBUS")
			(pintype "passive")
		)
	)
	(footprint "antmicro-footprints:R_0402_1005Metric"
		(layer "F.Cu")
		(at 91.242962 155.6415 -90)
		(descr "Resistor SMD 0402")
		(tags "resistor SMD 0402")
		(property "Reference" "R235"
			(at -1.535 0.395 90)
			(layer "F.SilkS")
			(effects
				(font
					(size 0.7 0.7)
					(thickness 0.15)
				)
				(justify right bottom)
			)
		)
		(property "Value" "R_10k_0402"
			(at -1.011843 1.772047 90)
			(layer "F.Fab")
			(effects
				(font
					(size 0.7 0.7)
					(thickness 0.15)
				)
				(justify right bottom)
			)
		)
		(property "Datasheet" "https://www.bourns.com/docs/product-datasheets/cr.pdf"
			(at 0 0 270)
			(layer "F.Fab")
			(hide yes)
			(effects
				(font
					(size 1.27 1.27)
					(thickness 0.15)
				)
			)
		)
		(property "MPN" "CR0402-FX-1002GLF"
			(at 0 0 270)
			(unlocked yes)
			(layer "F.Fab")
			(hide yes)
			(effects
				(font
					(size 1 1)
					(thickness 0.15)
				)
			)
		)
		(property "Manufacturer" "Bourns"
			(at 0 0 270)
			(unlocked yes)
			(layer "F.Fab")
			(hide yes)
			(effects
				(font
					(size 1 1)
					(thickness 0.15)
				)
			)
		)
		(property "License" "Apache-2.0"
			(at 0 0 270)
			(unlocked yes)
			(layer "F.Fab")
			(hide yes)
			(effects
				(font
					(size 1 1)
					(thickness 0.15)
				)
			)
		)
		(property "Author" "Antmicro"
			(at 0 0 270)
			(unlocked yes)
			(layer "F.Fab")
			(hide yes)
			(effects
				(font
					(size 1 1)
					(thickness 0.15)
				)
			)
		)
		(property "Val" "10k"
			(at 0 0 270)
			(unlocked yes)
			(layer "F.Fab")
			(hide yes)
			(effects
				(font
					(size 1 1)
					(thickness 0.15)
				)
			)
		)
		(property "Tolerance" "1%"
			(at 0 0 270)
			(unlocked yes)
			(layer "F.Fab")
			(hide yes)
			(effects
				(font
					(size 1 1)
					(thickness 0.15)
				)
			)
		)
		(sheetname "/Compute module/")
		(sheetfile "compute-module.kicad_sch")
		(attr smd)
		(fp_rect
			(start -0.925 -0.47)
			(end 0.925 0.47)
			(stroke
				(width 0.05)
				(type default)
			)
			(fill no)
			(layer "F.CrtYd")
		)
		(fp_rect
			(start -0.5 -0.25)
			(end 0.5 0.25)
			(stroke
				(width 0.15)
				(type solid)
			)
			(fill no)
			(layer "F.Fab")
		)
		(fp_text user "License: Apache-2.0"
			(at -0.95 5.169 270)
			(layer "F.Fab")
			(effects
				(font
					(size 0.7 0.7)
					(thickness 0.15)
				)
				(justify left bottom)
			)
		)
		(fp_text user "Author: Antmicro"
			(at -0.95 4.169 270)
			(layer "F.Fab")
			(effects
				(font
					(size 0.7 0.7)
					(thickness 0.15)
				)
				(justify left bottom)
			)
		)
		(fp_text user "${REFERENCE}"
			(at -0.95 3.168 270)
			(layer "F.Fab")
			(effects
				(font
					(size 0.7 0.7)
					(thickness 0.15)
				)
				(justify left bottom)
			)
		)
		(pad "1" smd roundrect
			(at -0.48 0 270)
			(size 0.59 0.64)
			(layers "F.Cu" "F.Mask" "F.Paste")
			(roundrect_rratio 0.25)
			(net 348 "Net-(U204-~{RESET})")
			(pintype "passive")
		)
		(pad "2" smd roundrect
			(at 0.48 0 270)
			(size 0.59 0.64)
			(layers "F.Cu" "F.Mask" "F.Paste")
			(roundrect_rratio 0.25)
			(net 9 "+3V3")
			(pintype "passive")
		)
	)
)
